(kicad_pcb
	(version 20260206)
	(generator "pcbnew")
	(generator_version "10.0")
	(general
		(thickness 1.6)
		(legacy_teardrops no)
	)
	(paper "A4")
	(title_block
		(title "Wiwynn_Tioga_Pass_MB.brd")
		(comment 1 "Tioga Pass / footprints 3774-3781 of 4770")
	)
	(layers
		(0 "F.Cu" signal "TOP")
		(4 "In1.Cu" signal "L2GND")
		(6 "In2.Cu" signal "L3")
		(8 "In3.Cu" signal "L4GND")
		(10 "In4.Cu" signal "L5")
		(12 "In5.Cu" signal "L6GND")
		(14 "In6.Cu" signal "L7VCC")
		(16 "In7.Cu" signal "L8VCC")
		(18 "In8.Cu" signal "L9GND")
		(20 "In9.Cu" signal "L10")
		(22 "In10.Cu" signal "L11GND")
		(24 "In11.Cu" signal "L12")
		(26 "In12.Cu" signal "L13GND")
		(2 "B.Cu" signal "BOTTOM")
		(9 "F.Adhes" user "F.Adhesive")
		(11 "B.Adhes" user "B.Adhesive")
		(13 "F.Paste" user "Package Geometry/Pastemask Top")
		(15 "B.Paste" user "Package Geometry/Pastemask Bottom")
		(5 "F.SilkS" user "Ref Des/Silkscreen Top")
		(7 "B.SilkS" user "Ref Des/Silkscreen Bottom")
		(1 "F.Mask" user "Board Geometry/Soldermask Top")
		(3 "B.Mask" user "Board Geometry/Soldermask Bottom")
		(17 "Dwgs.User" user "User.Drawings")
		(19 "Cmts.User" user "User.Comments")
		(21 "Eco1.User" user "User.Eco1")
		(23 "Eco2.User" user "User.Eco2")
		(25 "Edge.Cuts" user "Board Geometry/Outline")
		(27 "Margin" user)
		(31 "F.CrtYd" user "Package Geometry/Place Bound Top")
		(29 "B.CrtYd" user "Package Geometry/Place Bound Bottom")
		(35 "F.Fab" user "Ref Des/Assembly Top")
		(33 "B.Fab" user "Ref Des/Assembly Bottom")
	)
	(footprint ""
		(layer "B.Cu")
		(at 258.445 -17.6276 -90)
		(property "Reference" "C5T13"
			(at 0 0 90)
			(layer "B.SilkS")
			(hide yes)
			(effects
				(font
					(size 1.27 1.27)
				)
				(justify mirror)
			)
		)
		(property "Value" ""
			(at 0 0 90)
			(layer "B.Fab")
			(effects
				(font
					(size 1.27 1.27)
				)
				(justify mirror)
			)
		)
		(duplicate_pad_numbers_are_jumpers no)
		(fp_rect
			(start 0.500126 1.598422)
			(end -0.500126 -0.201422)
			(stroke
				(width 0)
				(type default)
			)
			(fill no)
			(layer "B.CrtYd")
		)
		(fp_line
			(start -0.500126 1.598422)
			(end 0.500126 1.598422)
			(stroke
				(width 0.1)
				(type default)
			)
			(layer "B.Fab")
		)
		(fp_line
			(start 0.500126 1.598422)
			(end 0.500126 -0.201422)
			(stroke
				(width 0.1)
				(type default)
			)
			(layer "B.Fab")
		)
		(fp_line
			(start -0.500126 -0.201422)
			(end -0.500126 1.598422)
			(stroke
				(width 0.1)
				(type default)
			)
			(layer "B.Fab")
		)
		(fp_line
			(start 0.500126 -0.201422)
			(end -0.500126 -0.201422)
			(stroke
				(width 0.1)
				(type default)
			)
			(layer "B.Fab")
		)
		(pad "1" smd rect
			(at 0 0 180)
			(size 0.889 0.9906)
			(layers "B.Cu" "B.Mask" "B.Paste")
			(net "PVDDQ_ABC")
		)
		(pad "2" smd rect
			(at 0 1.397 180)
			(size 0.889 0.9906)
			(layers "B.Cu" "B.Mask" "B.Paste")
			(net "GND")
		)
		(zone
			(layer "B.Cu")
			(hatch none 0.5)
			(connect_pads
				(clearance 0)
			)
			(min_thickness 0.25)
			(keepout
				(tracks not_allowed)
				(vias allowed)
				(pads allowed)
				(copperpour not_allowed)
				(footprints allowed)
			)
			(placement
				(enabled no)
				(sheetname "")
			)
			(fill
				(thermal_gap 0.5)
				(thermal_bridge_width 0.5)
				(island_removal_mode 0)
			)
			(polygon
				(pts
					(xy 257.4925 -17.1323) (xy 258.0005 -17.1323) (xy 258.0005 -18.1229) (xy 257.4925 -18.1229)
				)
			)
		)
		(zone
			(layer "B.Cu")
			(hatch none 0.5)
			(connect_pads
				(clearance 0)
			)
			(min_thickness 0.25)
			(keepout
				(tracks allowed)
				(vias not_allowed)
				(pads allowed)
				(copperpour not_allowed)
				(footprints allowed)
			)
			(placement
				(enabled no)
				(sheetname "")
			)
			(fill
				(thermal_gap 0.5)
				(thermal_bridge_width 0.5)
				(island_removal_mode 0)
			)
			(polygon
				(pts
					(xy 257.4925 -17.1323) (xy 258.0005 -17.1323) (xy 258.0005 -18.1229) (xy 257.4925 -18.1229)
				)
			)
		)
	)
	(footprint ""
		(layer "B.Cu")
		(at 353.64801 -141.689328 90)
		(property "Reference" "C7W11"
			(at 0 0 90)
			(layer "B.SilkS")
			(hide yes)
			(effects
				(font
					(size 1.27 1.27)
				)
				(justify mirror)
			)
		)
		(property "Value" "*"
			(at 0.0762 -6.2357 90)
			(unlocked yes)
			(layer "B.Fab")
			(hide yes)
			(effects
				(font
					(size 1.27 1.016)
					(thickness 0.1524)
				)
				(justify mirror)
			)
		)
		(property "Device Type" "SC22U16V5MX-4-GP_SMD-BCG5-SC22A"
			(at 0.0762 -8.2677 90)
			(unlocked yes)
			(layer "B.Fab")
			(hide yes)
			(effects
				(font
					(size 1.27 1.016)
					(thickness 0.1524)
				)
				(justify mirror)
			)
		)
		(duplicate_pad_numbers_are_jumpers no)
		(fp_line
			(start -0.635 0)
			(end 0.635 0)
			(stroke
				(width 0.508)
				(type default)
			)
			(layer "B.SilkS")
		)
		(fp_rect
			(start 0.9652 1.778)
			(end -0.9652 -1.778)
			(stroke
				(width 0)
				(type default)
			)
			(fill no)
			(layer "B.CrtYd")
		)
		(fp_poly
			(pts
				(xy 0.9652 -1.778) (xy -0.9652 -1.778) (xy -0.9652 1.778) (xy 0.9652 1.778)
			)
			(stroke
				(width 0)
				(type default)
			)
			(fill no)
			(layer "B.Fab")
		)
		(pad "1" smd rect
			(at 0 -0.9652 270)
			(size 1.397 1.143)
			(layers "B.Cu" "B.Mask" "B.Paste")
			(net "VR_FET_SW_P12V_STBY_PVDDQ_DEF")
		)
		(pad "2" smd rect
			(at 0 0.9652 270)
			(size 1.397 1.143)
			(layers "B.Cu" "B.Mask" "B.Paste")
			(net "GND")
		)
	)
	(footprint ""
		(layer "B.Cu")
		(at 157.08122 -124.0917)
		(property "Reference" "R7M2"
			(at 0 0 0)
			(layer "B.SilkS")
			(hide yes)
			(effects
				(font
					(size 1.27 1.27)
				)
				(justify mirror)
			)
		)
		(property "Value" ""
			(at 0 0 0)
			(layer "B.Fab")
			(effects
				(font
					(size 1.27 1.27)
				)
				(justify mirror)
			)
		)
		(duplicate_pad_numbers_are_jumpers no)
		(fp_poly
			(pts
				(xy 0.2794 -0.1016) (xy -0.2794 -0.1016) (xy -0.2794 0.9906) (xy 0.2794 0.9906)
			)
			(stroke
				(width 0)
				(type default)
			)
			(fill no)
			(layer "B.CrtYd")
		)
		(fp_line
			(start -0.2794 -0.1016)
			(end 0.2794 -0.1016)
			(stroke
				(width 0.1)
				(type default)
			)
			(layer "B.Fab")
		)
		(fp_line
			(start -0.2794 0.9906)
			(end -0.2794 -0.1016)
			(stroke
				(width 0.1)
				(type default)
			)
			(layer "B.Fab")
		)
		(fp_line
			(start 0.2794 -0.1016)
			(end 0.2794 0.9906)
			(stroke
				(width 0.1)
				(type default)
			)
			(layer "B.Fab")
		)
		(fp_line
			(start 0.2794 0.9906)
			(end -0.2794 0.9906)
			(stroke
				(width 0.1)
				(type default)
			)
			(layer "B.Fab")
		)
		(pad "1" smd rect
			(at 0 0 180)
			(size 0.508 0.508)
			(layers "B.Cu" "B.Mask" "B.Paste")
			(net "PVCCIO_CPU1")
		)
		(pad "2" smd rect
			(at 0 0.889 180)
			(size 0.508 0.508)
			(layers "B.Cu" "B.Mask" "B.Paste")
			(net "SMB_DDR_KLM_SCL_G")
		)
		(zone
			(layer "B.Cu")
			(hatch none 0.5)
			(connect_pads
				(clearance 0)
			)
			(min_thickness 0.25)
			(keepout
				(tracks allowed)
				(vias not_allowed)
				(pads allowed)
				(copperpour not_allowed)
				(footprints allowed)
			)
			(placement
				(enabled no)
				(sheetname "")
			)
			(fill
				(thermal_gap 0.5)
				(thermal_bridge_width 0.5)
				(island_removal_mode 0)
			)
			(polygon
				(pts
					(xy 157.33522 -123.8377) (xy 156.82722 -123.8377) (xy 156.82722 -123.4567) (xy 157.33522 -123.4567)
				)
			)
		)
		(zone
			(layer "B.Cu")
			(hatch none 0.5)
			(connect_pads
				(clearance 0)
			)
			(min_thickness 0.25)
			(keepout
				(tracks not_allowed)
				(vias allowed)
				(pads allowed)
				(copperpour not_allowed)
				(footprints allowed)
			)
			(placement
				(enabled no)
				(sheetname "")
			)
			(fill
				(thermal_gap 0.5)
				(thermal_bridge_width 0.5)
				(island_removal_mode 0)
			)
			(polygon
				(pts
					(xy 157.33522 -123.4567) (xy 156.82722 -123.4567) (xy 156.82722 -123.8377) (xy 157.33522 -123.8377)
				)
			)
		)
	)
	(footprint ""
		(layer "B.Cu")
		(at 15.75308 -76.37272 90)
		(property "Reference" "C9P12"
			(at 0 0 90)
			(layer "B.SilkS")
			(hide yes)
			(effects
				(font
					(size 1.27 1.27)
				)
				(justify mirror)
			)
		)
		(property "Value" ""
			(at 0 0 90)
			(layer "B.Fab")
			(effects
				(font
					(size 1.27 1.27)
				)
				(justify mirror)
			)
		)
		(duplicate_pad_numbers_are_jumpers no)
		(fp_rect
			(start -0.3048 -0.1016)
			(end 0.3048 0.9906)
			(stroke
				(width 0)
				(type default)
			)
			(fill no)
			(layer "B.CrtYd")
		)
		(fp_line
			(start 0.3048 -0.1016)
			(end 0.3048 0.9906)
			(stroke
				(width 0.1)
				(type default)
			)
			(layer "B.Fab")
		)
		(fp_line
			(start -0.3048 -0.1016)
			(end 0.3048 -0.1016)
			(stroke
				(width 0.1)
				(type default)
			)
			(layer "B.Fab")
		)
		(fp_line
			(start 0.3048 0.9906)
			(end -0.3048 0.9906)
			(stroke
				(width 0.1)
				(type default)
			)
			(layer "B.Fab")
		)
		(fp_line
			(start -0.3048 0.9906)
			(end -0.3048 -0.1016)
			(stroke
				(width 0.1)
				(type default)
			)
			(layer "B.Fab")
		)
		(pad "1" smd rect
			(at 0 0 270)
			(size 0.508 0.508)
			(layers "B.Cu" "B.Mask" "B.Paste")
			(net "A_HSC_VOUT")
		)
		(pad "2" smd rect
			(at 0 0.889 270)
			(size 0.508 0.508)
			(layers "B.Cu" "B.Mask" "B.Paste")
			(net "AGND_HSC")
		)
		(zone
			(layer "B.Cu")
			(hatch none 0.5)
			(connect_pads
				(clearance 0)
			)
			(min_thickness 0.25)
			(keepout
				(tracks allowed)
				(vias not_allowed)
				(pads allowed)
				(copperpour not_allowed)
				(footprints allowed)
			)
			(placement
				(enabled no)
				(sheetname "")
			)
			(fill
				(thermal_gap 0.5)
				(thermal_bridge_width 0.5)
				(island_removal_mode 0)
			)
			(polygon
				(pts
					(xy 16.00708 -76.11872) (xy 16.38808 -76.11872) (xy 16.38808 -76.62672) (xy 16.00708 -76.62672)
				)
			)
		)
		(zone
			(layer "B.Cu")
			(hatch none 0.5)
			(connect_pads
				(clearance 0)
			)
			(min_thickness 0.25)
			(keepout
				(tracks not_allowed)
				(vias allowed)
				(pads allowed)
				(copperpour not_allowed)
				(footprints allowed)
			)
			(placement
				(enabled no)
				(sheetname "")
			)
			(fill
				(thermal_gap 0.5)
				(thermal_bridge_width 0.5)
				(island_removal_mode 0)
			)
			(polygon
				(pts
					(xy 16.00708 -76.11872) (xy 16.38808 -76.11872) (xy 16.38808 -76.62672) (xy 16.00708 -76.62672)
				)
			)
		)
	)
	(footprint ""
		(layer "B.Cu")
		(at 361.444794 -46.496986 -90)
		(property "Reference" "R7D43"
			(at 0 0 90)
			(layer "B.SilkS")
			(hide yes)
			(effects
				(font
					(size 1.27 1.27)
				)
				(justify mirror)
			)
		)
		(property "Value" ""
			(at 0 0 90)
			(layer "B.Fab")
			(effects
				(font
					(size 1.27 1.27)
				)
				(justify mirror)
			)
		)
		(duplicate_pad_numbers_are_jumpers no)
		(fp_poly
			(pts
				(xy 0.2794 -0.1016) (xy -0.2794 -0.1016) (xy -0.2794 0.9906) (xy 0.2794 0.9906)
			)
			(stroke
				(width 0)
				(type default)
			)
			(fill no)
			(layer "B.CrtYd")
		)
		(fp_line
			(start -0.2794 0.9906)
			(end -0.2794 -0.1016)
			(stroke
				(width 0.1)
				(type default)
			)
			(layer "B.Fab")
		)
		(fp_line
			(start 0.2794 0.9906)
			(end -0.2794 0.9906)
			(stroke
				(width 0.1)
				(type default)
			)
			(layer "B.Fab")
		)
		(fp_line
			(start -0.2794 -0.1016)
			(end 0.2794 -0.1016)
			(stroke
				(width 0.1)
				(type default)
			)
			(layer "B.Fab")
		)
		(fp_line
			(start 0.2794 -0.1016)
			(end 0.2794 0.9906)
			(stroke
				(width 0.1)
				(type default)
			)
			(layer "B.Fab")
		)
		(pad "1" smd rect
			(at 0 0 90)
			(size 0.508 0.508)
			(layers "B.Cu" "B.Mask" "B.Paste")
			(net "FM_CPU1_PROCHOT_LVT3_K_N")
		)
		(pad "2" smd rect
			(at 0 0.889 90)
			(size 0.508 0.508)
			(layers "B.Cu" "B.Mask" "B.Paste")
			(net "H_CPU1_PROCHOT_G_PCH_N")
		)
		(zone
			(layer "B.Cu")
			(hatch none 0.5)
			(connect_pads
				(clearance 0)
			)
			(min_thickness 0.25)
			(keepout
				(tracks not_allowed)
				(vias allowed)
				(pads allowed)
				(copperpour not_allowed)
				(footprints allowed)
			)
			(placement
				(enabled no)
				(sheetname "")
			)
			(fill
				(thermal_gap 0.5)
				(thermal_bridge_width 0.5)
				(island_removal_mode 0)
			)
			(polygon
				(pts
					(xy 360.809794 -46.242986) (xy 360.809794 -46.750986) (xy 361.190794 -46.750986) (xy 361.190794 -46.242986)
				)
			)
		)
		(zone
			(layer "B.Cu")
			(hatch none 0.5)
			(connect_pads
				(clearance 0)
			)
			(min_thickness 0.25)
			(keepout
				(tracks allowed)
				(vias not_allowed)
				(pads allowed)
				(copperpour not_allowed)
				(footprints allowed)
			)
			(placement
				(enabled no)
				(sheetname "")
			)
			(fill
				(thermal_gap 0.5)
				(thermal_bridge_width 0.5)
				(island_removal_mode 0)
			)
			(polygon
				(pts
					(xy 361.190794 -46.242986) (xy 361.190794 -46.750986) (xy 360.809794 -46.750986) (xy 360.809794 -46.242986)
				)
			)
		)
	)
	(footprint ""
		(layer "B.Cu")
		(at 454.740772 -35.174174 90)
		(property "Reference" "U8D2"
			(at 0.508 1.92913 270)
			(unlocked yes)
			(layer "B.SilkS")
			(effects
				(font
					(size 0.7874 0.5842)
					(thickness 0.1524)
				)
				(justify left mirror)
			)
		)
		(property "Value" ""
			(at 0 0 90)
			(layer "B.Fab")
			(effects
				(font
					(size 1.27 1.27)
				)
				(justify mirror)
			)
		)
		(duplicate_pad_numbers_are_jumpers no)
		(fp_circle
			(center 0.4699 -0.8382)
			(end 0.4699 -0.7112)
			(stroke
				(width 0.254)
				(type default)
			)
			(fill no)
			(layer "B.SilkS")
		)
		(fp_poly
			(pts
				(xy -0.21463 -0.450088) (xy -1.56337 -0.450088) (xy -1.56337 1.75006) (xy -0.21463 1.75006)
			)
			(stroke
				(width 0)
				(type default)
			)
			(fill no)
			(layer "B.CrtYd")
		)
		(fp_line
			(start -0.21463 -0.450088)
			(end -1.56337 -0.450088)
			(stroke
				(width 0.1)
				(type default)
			)
			(layer "B.Fab")
		)
		(fp_line
			(start -1.56337 -0.450088)
			(end -1.56337 1.75006)
			(stroke
				(width 0.1)
				(type default)
			)
			(layer "B.Fab")
		)
		(fp_line
			(start -0.21463 1.75006)
			(end -0.21463 -0.450088)
			(stroke
				(width 0.1)
				(type default)
			)
			(layer "B.Fab")
		)
		(fp_line
			(start -1.56337 1.75006)
			(end -0.21463 1.75006)
			(stroke
				(width 0.1)
				(type default)
			)
			(layer "B.Fab")
		)
		(fp_circle
			(center 0.4699 -0.8382)
			(end 0.4699 -0.7112)
			(stroke
				(width 0.254)
				(type default)
			)
			(fill no)
			(layer "B.Fab")
		)
		(pad "1" smd rect
			(at 0 0 270)
			(size 1.016 0.381)
			(layers "B.Cu" "B.Mask" "B.Paste")
			(net "Net_6477")
		)
		(pad "2" smd rect
			(at 0 0.649986 270)
			(size 1.016 0.381)
			(layers "B.Cu" "B.Mask" "B.Paste")
			(net "PWRGD_DSW_PWROK")
		)
		(pad "3" smd rect
			(at 0 1.299972 270)
			(size 1.016 0.381)
			(layers "B.Cu" "B.Mask" "B.Paste")
			(net "GND")
		)
		(pad "4" smd rect
			(at -1.778 1.299972 270)
			(size 1.016 0.381)
			(layers "B.Cu" "B.Mask" "B.Paste")
			(net "RST_BMC_SRST_R2_N")
		)
		(pad "5" smd rect
			(at -1.778 0 270)
			(size 1.016 0.381)
			(layers "B.Cu" "B.Mask" "B.Paste")
			(net "P3V3_STBY")
		)
	)
	(footprint ""
		(layer "B.Cu")
		(at 459.867 -116.49202)
		(property "Reference" "C1M10"
			(at 0 0 0)
			(layer "B.SilkS")
			(hide yes)
			(effects
				(font
					(size 1.27 1.27)
				)
				(justify mirror)
			)
		)
		(property "Value" ""
			(at 0 0 0)
			(layer "B.Fab")
			(effects
				(font
					(size 1.27 1.27)
				)
				(justify mirror)
			)
		)
		(duplicate_pad_numbers_are_jumpers no)
		(fp_rect
			(start -0.3048 0.9906)
			(end 0.3048 -0.1016)
			(stroke
				(width 0)
				(type default)
			)
			(fill no)
			(layer "B.CrtYd")
		)
		(fp_line
			(start -0.3048 -0.1016)
			(end 0.3048 -0.1016)
			(stroke
				(width 0.1)
				(type default)
			)
			(layer "B.Fab")
		)
		(fp_line
			(start -0.3048 0.9906)
			(end -0.3048 -0.1016)
			(stroke
				(width 0.1)
				(type default)
			)
			(layer "B.Fab")
		)
		(fp_line
			(start 0.3048 -0.1016)
			(end 0.3048 0.9906)
			(stroke
				(width 0.1)
				(type default)
			)
			(layer "B.Fab")
		)
		(fp_line
			(start 0.3048 0.9906)
			(end -0.3048 0.9906)
			(stroke
				(width 0.1)
				(type default)
			)
			(layer "B.Fab")
		)
		(pad "1" smd rect
			(at 0 0 180)
			(size 0.508 0.508)
			(layers "B.Cu" "B.Mask" "B.Paste")
			(net "P3E_CPU0_PE3_OCP_TXP<13>")
		)
		(pad "2" smd rect
			(at 0 0.889 180)
			(size 0.508 0.508)
			(layers "B.Cu" "B.Mask" "B.Paste")
			(net "P3E_OCP_CPU0_PE3_C_TXP<13>")
		)
		(zone
			(layer "B.Cu")
			(hatch none 0.5)
			(connect_pads
				(clearance 0)
			)
			(min_thickness 0.25)
			(keepout
				(tracks allowed)
				(vias not_allowed)
				(pads allowed)
				(copperpour not_allowed)
				(footprints allowed)
			)
			(placement
				(enabled no)
				(sheetname "")
			)
			(fill
				(thermal_gap 0.5)
				(thermal_bridge_width 0.5)
				(island_removal_mode 0)
			)
			(polygon
				(pts
					(xy 459.613 -115.85702) (xy 460.121 -115.85702) (xy 460.121 -116.23802) (xy 459.613 -116.23802)
				)
			)
		)
		(zone
			(layer "B.Cu")
			(hatch none 0.5)
			(connect_pads
				(clearance 0)
			)
			(min_thickness 0.25)
			(keepout
				(tracks not_allowed)
				(vias allowed)
				(pads allowed)
				(copperpour not_allowed)
				(footprints allowed)
			)
			(placement
				(enabled no)
				(sheetname "")
			)
			(fill
				(thermal_gap 0.5)
				(thermal_bridge_width 0.5)
				(island_removal_mode 0)
			)
			(polygon
				(pts
					(xy 459.613 -115.85702) (xy 460.121 -115.85702) (xy 460.121 -116.23802) (xy 459.613 -116.23802)
				)
			)
		)
	)
	(footprint ""
		(layer "B.Cu")
		(at 377.698 -19.558)
		(property "Reference" "RN8F3"
			(at 0.8382 -0.67818 0)
			(unlocked yes)
			(layer "B.SilkS")
			(effects
				(font
					(size 0.4064 0.254)
					(thickness 0.1524)
				)
				(justify left mirror)
			)
		)
		(property "Value" ""
			(at 0 0 0)
			(layer "B.Fab")
			(effects
				(font
					(size 1.27 1.27)
				)
				(justify mirror)
			)
		)
		(duplicate_pad_numbers_are_jumpers no)
		(fp_poly
			(pts
				(xy 0.2794 -0.1016) (xy -0.2794 -0.1016) (xy -0.2794 0.9906) (xy 0.2794 0.9906)
			)
			(stroke
				(width 0)
				(type default)
			)
			(fill no)
			(layer "B.CrtYd")
		)
		(fp_line
			(start -0.2794 -0.1016)
			(end 0.2794 -0.1016)
			(stroke
				(width 0.1)
				(type default)
			)
			(layer "B.Fab")
		)
		(fp_line
			(start -0.2794 0.9906)
			(end -0.2794 -0.1016)
			(stroke
				(width 0.1)
				(type default)
			)
			(layer "B.Fab")
		)
		(fp_line
			(start 0.2794 -0.1016)
			(end 0.2794 0.9906)
			(stroke
				(width 0.1)
				(type default)
			)
			(layer "B.Fab")
		)
		(fp_line
			(start 0.2794 0.9906)
			(end -0.2794 0.9906)
			(stroke
				(width 0.1)
				(type default)
			)
			(layer "B.Fab")
		)
		(pad "1" smd rect
			(at 0 0 180)
			(size 0.508 0.508)
			(layers "B.Cu" "B.Mask" "B.Paste")
			(net "P3V3_STBY")
		)
		(pad "2" smd rect
			(at 0 0.889 180)
			(size 0.508 0.508)
			(layers "B.Cu" "B.Mask" "B.Paste")
			(net "PU_TPM_SPI_BMC_HOLD_N")
		)
		(zone
			(layer "B.Cu")
			(hatch none 0.5)
			(connect_pads
				(clearance 0)
			)
			(min_thickness 0.25)
			(keepout
				(tracks allowed)
				(vias not_allowed)
				(pads allowed)
				(copperpour not_allowed)
				(footprints allowed)
			)
			(placement
				(enabled no)
				(sheetname "")
			)
			(fill
				(thermal_gap 0.5)
				(thermal_bridge_width 0.5)
				(island_removal_mode 0)
			)
			(polygon
				(pts
					(xy 377.952 -19.304) (xy 377.444 -19.304) (xy 377.444 -18.923) (xy 377.952 -18.923)
				)
			)
		)
		(zone
			(layer "B.Cu")
			(hatch none 0.5)
			(connect_pads
				(clearance 0)
			)
			(min_thickness 0.25)
			(keepout
				(tracks not_allowed)
				(vias allowed)
				(pads allowed)
				(copperpour not_allowed)
				(footprints allowed)
			)
			(placement
				(enabled no)
				(sheetname "")
			)
			(fill
				(thermal_gap 0.5)
				(thermal_bridge_width 0.5)
				(island_removal_mode 0)
			)
			(polygon
				(pts
					(xy 377.952 -18.923) (xy 377.444 -18.923) (xy 377.444 -19.304) (xy 377.952 -19.304)
				)
			)
		)
	)
)
